# T6G (Grand Teton) — schematic netlist excerpt (pin names and nets, part order shuffled) for the footprints in the layout excerpt that follows; sources: Cadence DE-HDL packaged netlist, KiCad conversion of 04192023_DAF0TMB3IC0_F0TG_MB_C_brd_V02_OCP.brd

U266  ISL28022FRZT  ISL28022FRZ-T IC  pkg QFN16_TH_0-5_3X3XH  page 236
  A1  = INA230_1_A1
  A0  = INA230_1_A0
  \ext_clk||int\  = OCP_SFF_P3V3_ADC_ALERT_R
  \sda||smbdat\  = SMB_INA230_1_3V3AUX_SDA_R1
  \scl|||smbclk\  = SMB_INA230_1_3V3AUX_SCL_R1
  NC0  = NC_INA230_1_NC0
  NC1  = NC_INA230_1_NC1
  NC2  = NC_INA230_1_NC2
  VCC  = P3V3_AUX
  GND  = GND
  VBUS  = P3V3_OCP_SFF_R
  VINM  = VSENSE_P3V3_INA230_1_INN
  VINP  = VSENSE_P3V3_INA230_1_INP
  NC3  = NC_INA230_1_NC3
  NC4  = NC_INA230_1_NC4
  NC5  = NC_INA230_1_NC5
  TH_GND  = GND

(kicad_pcb
	(version 20260206)
	(generator "pcbnew")
	(generator_version "10.0")
	(general
		(thickness 1.6)
		(legacy_teardrops no)
	)
	(paper "A4")
	(title_block
		(title "04192023_DAF0TMB3IC0_F0TG_MB_C_brd_V02_OCP.brd")
		(comment 1 "Grand Teton / footprints 1942-1942 of 8354")
	)
	(layers
		(0 "F.Cu" signal "TOP")
		(4 "In1.Cu" signal "GND")
		(6 "In2.Cu" signal "IN1")
		(8 "In3.Cu" signal "GND1")
		(10 "In4.Cu" signal "IN2")
		(12 "In5.Cu" signal "GND2")
		(14 "In6.Cu" signal "IN3")
		(16 "In7.Cu" signal "GND3")
		(18 "In8.Cu" signal "VCC")
		(20 "In9.Cu" signal "VCC1")
		(22 "In10.Cu" signal "GND4")
		(24 "In11.Cu" signal "IN4")
		(26 "In12.Cu" signal "GND5")
		(28 "In13.Cu" signal "IN5")
		(30 "In14.Cu" signal "GND6")
		(32 "In15.Cu" signal "IN6")
		(34 "In16.Cu" signal "GND7")
		(2 "B.Cu" signal "BOTTOM")
		(9 "F.Adhes" user "F.Adhesive")
		(11 "B.Adhes" user "B.Adhesive")
		(13 "F.Paste" user "Package Geometry/Pastemask Top")
		(15 "B.Paste" user "Package Geometry/Pastemask Bottom")
		(5 "F.SilkS" user "Ref Des/Silkscreen Top")
		(7 "B.SilkS" user "Ref Des/Silkscreen Bottom")
		(1 "F.Mask" user "Board Geometry/Soldermask Top")
		(3 "B.Mask" user "Board Geometry/Soldermask Bottom")
		(17 "Dwgs.User" user "User.Drawings")
		(19 "Cmts.User" user "User.Comments")
		(21 "Eco1.User" user "User.Eco1")
		(23 "Eco2.User" user "User.Eco2")
		(25 "Edge.Cuts" user "Board Geometry/Outline")
		(27 "Margin" user)
		(31 "F.CrtYd" user "Package Geometry/Place Bound Top")
		(29 "B.CrtYd" user "Package Geometry/Place Bound Bottom")
		(35 "F.Fab" user "Ref Des/Assembly Top")
		(33 "B.Fab" user "Ref Des/Assembly Bottom")
	)
	(footprint ""
		(layer "F.Cu")
		(at 440.687968 -94.077536 180)
		(property "Reference" "U266"
			(at 0.221996 2.912872 0)
			(unlocked yes)
			(layer "F.SilkS")
			(effects
				(font
					(size 0.7874 0.5842)
					(thickness 0.1524)
				)
			)
		)
		(property "Value" ""
			(at 0 0 180)
			(layer "F.Fab")
			(effects
				(font
					(size 1.27 1.27)
				)
			)
		)
		(duplicate_pad_numbers_are_jumpers no)
		(fp_line
			(start 1.500124 1.500124)
			(end 1.004062 1.500124)
			(stroke
				(width 0.1524)
				(type default)
			)
			(layer "F.SilkS")
		)
		(fp_line
			(start 1.500124 1.004062)
			(end 1.500124 1.500124)
			(stroke
				(width 0.1524)
				(type default)
			)
			(layer "F.SilkS")
		)
		(fp_line
			(start 1.500124 -1.500124)
			(end 1.500124 -1.004062)
			(stroke
				(width 0.1524)
				(type default)
			)
			(layer "F.SilkS")
		)
		(fp_line
			(start 1.004062 -1.500124)
			(end 1.500124 -1.500124)
			(stroke
				(width 0.1524)
				(type default)
			)
			(layer "F.SilkS")
		)
		(fp_line
			(start -1.004062 1.500124)
			(end -1.500124 1.500124)
			(stroke
				(width 0.1524)
				(type default)
			)
			(layer "F.SilkS")
		)
		(fp_line
			(start -1.500124 1.500124)
			(end -1.500124 1.004062)
			(stroke
				(width 0.1524)
				(type default)
			)
			(layer "F.SilkS")
		)
		(fp_line
			(start -1.500124 -1.004062)
			(end -1.500124 -1.500124)
			(stroke
				(width 0.1524)
				(type default)
			)
			(layer "F.SilkS")
		)
		(fp_line
			(start -1.500124 -1.500124)
			(end -1.004062 -1.500124)
			(stroke
				(width 0.1524)
				(type default)
			)
			(layer "F.SilkS")
		)
		(fp_poly
			(pts
				(xy -2.242312 -0.54102) (xy -2.242312 -0.999744) (xy -1.783588 -0.770382)
			)
			(stroke
				(width 0)
				(type default)
			)
			(fill yes)
			(layer "F.SilkS")
		)
		(fp_line
			(start 1.500124 1.500124)
			(end -1.500124 1.500124)
			(stroke
				(width 0.1)
				(type default)
			)
			(layer "F.Fab")
		)
		(fp_line
			(start 1.500124 -1.500124)
			(end 1.500124 1.500124)
			(stroke
				(width 0.1)
				(type default)
			)
			(layer "F.Fab")
		)
		(fp_line
			(start -1.500124 1.500124)
			(end -1.500124 -1.500124)
			(stroke
				(width 0.1)
				(type default)
			)
			(layer "F.Fab")
		)
		(fp_line
			(start -1.500124 -1.500124)
			(end 1.500124 -1.500124)
			(stroke
				(width 0.1)
				(type default)
			)
			(layer "F.Fab")
		)
		(fp_poly
			(pts
				(xy -2.847848 -1.258062) (xy -2.847848 -0.242062) (xy -1.831848 -0.750062)
			)
			(stroke
				(width 0)
				(type default)
			)
			(fill yes)
			(layer "F.Fab")
		)
		(pad "1" smd rect
			(at -1.400048 -0.750062 90)
			(size 0.2286 0.6096)
			(layers "F.Cu" "F.Mask" "F.Paste")
			(net "INA230_1_A1")
		)
		(pad "2" smd rect
			(at -1.400048 -0.249936 90)
			(size 0.2286 0.6096)
			(layers "F.Cu" "F.Mask" "F.Paste")
			(net "INA230_1_A0")
		)
		(pad "3" smd rect
			(at -1.400048 0.249936 90)
			(size 0.2286 0.6096)
			(layers "F.Cu" "F.Mask" "F.Paste")
			(net "OCP_SFF_P3V3_ADC_ALERT_R")
		)
		(pad "4" smd rect
			(at -1.400048 0.750062 90)
			(size 0.2286 0.6096)
			(layers "F.Cu" "F.Mask" "F.Paste")
			(net "SMB_INA230_1_3V3AUX_SDA_R1")
		)
		(pad "5" smd rect
			(at -0.750062 1.400048 180)
			(size 0.2286 0.6096)
			(layers "F.Cu" "F.Mask" "F.Paste")
			(net "SMB_INA230_1_3V3AUX_SCL_R1")
		)
		(pad "6" smd rect
			(at -0.249936 1.400048 180)
			(size 0.2286 0.6096)
			(layers "F.Cu" "F.Mask" "F.Paste")
			(net "NC_INA230_1_NC0")
		)
		(pad "7" smd rect
			(at 0.249936 1.400048 180)
			(size 0.2286 0.6096)
			(layers "F.Cu" "F.Mask" "F.Paste")
			(net "NC_INA230_1_NC1")
		)
		(pad "8" smd rect
			(at 0.750062 1.400048 180)
			(size 0.2286 0.6096)
			(layers "F.Cu" "F.Mask" "F.Paste")
			(net "NC_INA230_1_NC2")
		)
		(pad "9" smd rect
			(at 1.400048 0.750062 90)
			(size 0.2286 0.6096)
			(layers "F.Cu" "F.Mask" "F.Paste")
			(net "P3V3_AUX")
		)
		(pad "10" smd rect
			(at 1.400048 0.249936 90)
			(size 0.2286 0.6096)
			(layers "F.Cu" "F.Mask" "F.Paste")
			(net "GND")
		)
		(pad "11" smd rect
			(at 1.400048 -0.249936 90)
			(size 0.2286 0.6096)
			(layers "F.Cu" "F.Mask" "F.Paste")
			(net "P3V3_OCP_SFF_R")
		)
		(pad "12" smd rect
			(at 1.400048 -0.750062 90)
			(size 0.2286 0.6096)
			(layers "F.Cu" "F.Mask" "F.Paste")
			(net "VSENSE_P3V3_INA230_1_INN")
		)
		(pad "13" smd rect
			(at 0.750062 -1.400048 180)
			(size 0.2286 0.6096)
			(layers "F.Cu" "F.Mask" "F.Paste")
			(net "VSENSE_P3V3_INA230_1_INP")
		)
		(pad "14" smd rect
			(at 0.249936 -1.400048 180)
			(size 0.2286 0.6096)
			(layers "F.Cu" "F.Mask" "F.Paste")
			(net "NC_INA230_1_NC3")
		)
		(pad "15" smd rect
			(at -0.249936 -1.400048 180)
			(size 0.2286 0.6096)
			(layers "F.Cu" "F.Mask" "F.Paste")
			(net "NC_INA230_1_NC4")
		)
		(pad "16" smd rect
			(at -0.750062 -1.400048 180)
			(size 0.2286 0.6096)
			(layers "F.Cu" "F.Mask" "F.Paste")
			(net "NC_INA230_1_NC5")
		)
		(pad "TH" smd rect
			(at 0 0 180)
			(size 1.7018 1.7018)
			(layers "F.Cu" "F.Mask" "F.Paste")
			(net "GND")
		)
		(zone
			(layer "F.Cu")
			(hatch none 0.5)
			(connect_pads
				(clearance 0)
			)
			(min_thickness 0.25)
			(keepout
				(tracks not_allowed)
				(vias allowed)
				(pads allowed)
				(copperpour not_allowed)
				(footprints allowed)
			)
			(placement
				(enabled no)
				(sheetname "")
			)
			(fill
				(thermal_gap 0.5)
				(thermal_bridge_width 0.5)
				(island_removal_mode 0)
			)
			(polygon
				(pts
					(xy 441.732416 -94.052136) (xy 441.732416 -93.033088) (xy 439.64352 -93.033088) (xy 439.64352 -95.121984)
					(xy 441.732416 -95.121984) (xy 441.732416 -94.077536) (xy 441.589668 -94.077536) (xy 441.589668 -94.979236)
					(xy 439.786268 -94.979236) (xy 439.786268 -93.175836) (xy 441.589668 -93.175836) (xy 441.589668 -94.052136)
				)
			)
		)
	)
)
